# S9S_MB_2U (Grand Teton) — schematic netlist excerpt (pin names and nets, part order shuffled) for the footprints in the layout excerpt that follows; sources: Cadence DE-HDL packaged netlist, KiCad conversion of 03242023_DA0F0TMBIJ0_F0T_Motherboard_J_brd_V01_OCP.brd

R2706  Q_RES  0 5% CHIP  pkg 0402LF  page 234 : A = I3C_BMC_SWB_R_SDA ; B = I3C_BMC_SWB_BUF_R_SDA
R1547  Q_RES  0 5% CHIP  pkg 0402LF  page 213 : A = FM_TPM_PRSNT_R_N ; B = FM_TPM_PRSNT_N
C1572  Q_CAP_DIFFBUS  DIFF BUS_0.22UF 6.3V 20% X6S  pkg C0201  page 175 : \1\ = P5E_CPU0_PE4_TX_C_DN<3> ; \2\ = P5E_CPU0_PE4_TX_DN<3>

(kicad_pcb
	(version 20260206)
	(generator "pcbnew")
	(generator_version "10.0")
	(general
		(thickness 1.6)
		(legacy_teardrops no)
	)
	(paper "A4")
	(title_block
		(title "03242023_DA0F0TMBIJ0_F0T_Motherboard_J_brd_V01_OCP.brd")
		(comment 1 "Grand Teton / footprints 2153-2155 of 6105")
	)
	(layers
		(0 "F.Cu" signal "TOP")
		(4 "In1.Cu" signal "GND")
		(6 "In2.Cu" signal "IN1")
		(8 "In3.Cu" signal "GND1")
		(10 "In4.Cu" signal "IN2")
		(12 "In5.Cu" signal "GND2")
		(14 "In6.Cu" signal "IN3")
		(16 "In7.Cu" signal "GND3")
		(18 "In8.Cu" signal "VCC")
		(20 "In9.Cu" signal "VCC1")
		(22 "In10.Cu" signal "GND4")
		(24 "In11.Cu" signal "IN4")
		(26 "In12.Cu" signal "GND5")
		(28 "In13.Cu" signal "IN5")
		(30 "In14.Cu" signal "GND6")
		(32 "In15.Cu" signal "IN6")
		(34 "In16.Cu" signal "GND7")
		(2 "B.Cu" signal "BOTTOM")
		(9 "F.Adhes" user "F.Adhesive")
		(11 "B.Adhes" user "B.Adhesive")
		(13 "F.Paste" user "Package Geometry/Pastemask Top")
		(15 "B.Paste" user "Package Geometry/Pastemask Bottom")
		(5 "F.SilkS" user "Ref Des/Silkscreen Top")
		(7 "B.SilkS" user "Ref Des/Silkscreen Bottom")
		(1 "F.Mask" user "Board Geometry/Soldermask Top")
		(3 "B.Mask" user "Board Geometry/Soldermask Bottom")
		(17 "Dwgs.User" user "User.Drawings")
		(19 "Cmts.User" user "User.Comments")
		(21 "Eco1.User" user "User.Eco1")
		(23 "Eco2.User" user "User.Eco2")
		(25 "Edge.Cuts" user "Board Geometry/Outline")
		(27 "Margin" user)
		(31 "F.CrtYd" user "Package Geometry/Place Bound Top")
		(29 "B.CrtYd" user "Package Geometry/Place Bound Bottom")
		(35 "F.Fab" user "Ref Des/Assembly Top")
		(33 "B.Fab" user "Ref Des/Assembly Bottom")
	)
	(footprint ""
		(layer "F.Cu")
		(at 369.292632 -396.249398)
		(property "Reference" "R2706"
			(at 0 0 0)
			(layer "F.SilkS")
			(hide yes)
			(effects
				(font
					(size 1.27 1.27)
				)
			)
		)
		(property "Value" ""
			(at 0 0 0)
			(layer "F.Fab")
			(effects
				(font
					(size 1.27 1.27)
				)
			)
		)
		(duplicate_pad_numbers_are_jumpers no)
		(fp_line
			(start -0.7874 -0.4064)
			(end 0.7874 -0.4064)
			(stroke
				(width 0.1524)
				(type default)
			)
			(layer "F.SilkS")
		)
		(fp_line
			(start -0.7874 0.4064)
			(end -0.7874 -0.4064)
			(stroke
				(width 0.1524)
				(type default)
			)
			(layer "F.SilkS")
		)
		(fp_line
			(start 0.7874 -0.4064)
			(end 0.7874 0.4064)
			(stroke
				(width 0.1524)
				(type default)
			)
			(layer "F.SilkS")
		)
		(fp_line
			(start 0.7874 0.4064)
			(end -0.7874 0.4064)
			(stroke
				(width 0.1524)
				(type default)
			)
			(layer "F.SilkS")
		)
		(fp_line
			(start -0.67945 -0.305054)
			(end -0.12065 -0.305054)
			(stroke
				(width 0.1)
				(type default)
			)
			(layer "F.Fab")
		)
		(fp_line
			(start -0.67945 0.3048)
			(end -0.67945 -0.305054)
			(stroke
				(width 0.1)
				(type default)
			)
			(layer "F.Fab")
		)
		(fp_line
			(start -0.12065 -0.305054)
			(end -0.12065 -0.2794)
			(stroke
				(width 0.1)
				(type default)
			)
			(layer "F.Fab")
		)
		(fp_line
			(start -0.12065 -0.2794)
			(end 0.12065 -0.2794)
			(stroke
				(width 0.1)
				(type default)
			)
			(layer "F.Fab")
		)
		(fp_line
			(start -0.12065 0.2794)
			(end -0.12065 0.3048)
			(stroke
				(width 0.1)
				(type default)
			)
			(layer "F.Fab")
		)
		(fp_line
			(start -0.12065 0.3048)
			(end -0.67945 0.3048)
			(stroke
				(width 0.1)
				(type default)
			)
			(layer "F.Fab")
		)
		(fp_line
			(start 0.120396 0.2794)
			(end -0.12065 0.2794)
			(stroke
				(width 0.1)
				(type default)
			)
			(layer "F.Fab")
		)
		(fp_line
			(start 0.120396 0.3048)
			(end 0.120396 0.2794)
			(stroke
				(width 0.1)
				(type default)
			)
			(layer "F.Fab")
		)
		(fp_line
			(start 0.12065 -0.3048)
			(end 0.67945 -0.3048)
			(stroke
				(width 0.1)
				(type default)
			)
			(layer "F.Fab")
		)
		(fp_line
			(start 0.12065 -0.2794)
			(end 0.12065 -0.3048)
			(stroke
				(width 0.1)
				(type default)
			)
			(layer "F.Fab")
		)
		(fp_line
			(start 0.67945 -0.3048)
			(end 0.67945 0.3048)
			(stroke
				(width 0.1)
				(type default)
			)
			(layer "F.Fab")
		)
		(fp_line
			(start 0.67945 0.3048)
			(end 0.120396 0.3048)
			(stroke
				(width 0.1)
				(type default)
			)
			(layer "F.Fab")
		)
		(pad "1" smd circle
			(at -0.40005 0)
			(size 0 0)
			(layers "F.Cu" "F.Mask" "F.Paste")
			(net "I3C_BMC_SWB_R_SDA")
		)
		(pad "2" smd circle
			(at 0.40005 0)
			(size 0 0)
			(layers "F.Cu" "F.Mask" "F.Paste")
			(net "I3C_BMC_SWB_BUF_R_SDA")
		)
	)
	(footprint ""
		(layer "F.Cu")
		(at 313.144408 -402.371052 -90)
		(property "Reference" "C1572"
			(at 0 0 270)
			(layer "F.SilkS")
			(hide yes)
			(effects
				(font
					(size 1.27 1.27)
				)
			)
		)
		(property "Value" ""
			(at 0 0 270)
			(layer "F.Fab")
			(effects
				(font
					(size 1.27 1.27)
				)
			)
		)
		(duplicate_pad_numbers_are_jumpers no)
		(fp_line
			(start -0.299974 0.150114)
			(end -0.299974 -0.150114)
			(stroke
				(width 0.1)
				(type default)
			)
			(layer "F.Fab")
		)
		(fp_line
			(start 0.299974 0.150114)
			(end -0.299974 0.150114)
			(stroke
				(width 0.1)
				(type default)
			)
			(layer "F.Fab")
		)
		(fp_line
			(start -0.299974 -0.150114)
			(end 0.299974 -0.150114)
			(stroke
				(width 0.1)
				(type default)
			)
			(layer "F.Fab")
		)
		(fp_line
			(start 0.299974 -0.150114)
			(end 0.299974 0.150114)
			(stroke
				(width 0.1)
				(type default)
			)
			(layer "F.Fab")
		)
		(pad "1" smd rect
			(at -0.2667 0 270)
			(size 0.3048 0.381)
			(layers "F.Cu" "F.Mask" "F.Paste")
			(net "P5E_CPU0_PE4_TX_C_DN<3>")
		)
		(pad "2" smd rect
			(at 0.2667 0 270)
			(size 0.3048 0.381)
			(layers "F.Cu" "F.Mask" "F.Paste")
			(net "P5E_CPU0_PE4_TX_DN<3>")
		)
	)
	(footprint ""
		(layer "F.Cu")
		(at 164.64788 -108.295948 180)
		(property "Reference" "R1547"
			(at 0 0 180)
			(layer "F.SilkS")
			(hide yes)
			(effects
				(font
					(size 1.27 1.27)
				)
			)
		)
		(property "Value" ""
			(at 0 0 180)
			(layer "F.Fab")
			(effects
				(font
					(size 1.27 1.27)
				)
			)
		)
		(duplicate_pad_numbers_are_jumpers no)
		(fp_line
			(start 0.7874 0.4064)
			(end -0.7874 0.4064)
			(stroke
				(width 0.1524)
				(type default)
			)
			(layer "F.SilkS")
		)
		(fp_line
			(start 0.7874 -0.4064)
			(end 0.7874 0.4064)
			(stroke
				(width 0.1524)
				(type default)
			)
			(layer "F.SilkS")
		)
		(fp_line
			(start -0.7874 0.4064)
			(end -0.7874 -0.4064)
			(stroke
				(width 0.1524)
				(type default)
			)
			(layer "F.SilkS")
		)
		(fp_line
			(start -0.7874 -0.4064)
			(end 0.7874 -0.4064)
			(stroke
				(width 0.1524)
				(type default)
			)
			(layer "F.SilkS")
		)
		(fp_line
			(start 0.67945 0.3048)
			(end 0.120396 0.3048)
			(stroke
				(width 0.1)
				(type default)
			)
			(layer "F.Fab")
		)
		(fp_line
			(start 0.67945 -0.3048)
			(end 0.67945 0.3048)
			(stroke
				(width 0.1)
				(type default)
			)
			(layer "F.Fab")
		)
		(fp_line
			(start 0.12065 -0.2794)
			(end 0.12065 -0.3048)
			(stroke
				(width 0.1)
				(type default)
			)
			(layer "F.Fab")
		)
		(fp_line
			(start 0.12065 -0.3048)
			(end 0.67945 -0.3048)
			(stroke
				(width 0.1)
				(type default)
			)
			(layer "F.Fab")
		)
		(fp_line
			(start 0.120396 0.3048)
			(end 0.120396 0.2794)
			(stroke
				(width 0.1)
				(type default)
			)
			(layer "F.Fab")
		)
		(fp_line
			(start 0.120396 0.2794)
			(end -0.12065 0.2794)
			(stroke
				(width 0.1)
				(type default)
			)
			(layer "F.Fab")
		)
		(fp_line
			(start -0.12065 0.3048)
			(end -0.67945 0.3048)
			(stroke
				(width 0.1)
				(type default)
			)
			(layer "F.Fab")
		)
		(fp_line
			(start -0.12065 0.2794)
			(end -0.12065 0.3048)
			(stroke
				(width 0.1)
				(type default)
			)
			(layer "F.Fab")
		)
		(fp_line
			(start -0.12065 -0.2794)
			(end 0.12065 -0.2794)
			(stroke
				(width 0.1)
				(type default)
			)
			(layer "F.Fab")
		)
		(fp_line
			(start -0.12065 -0.305054)
			(end -0.12065 -0.2794)
			(stroke
				(width 0.1)
				(type default)
			)
			(layer "F.Fab")
		)
		(fp_line
			(start -0.67945 0.3048)
			(end -0.67945 -0.305054)
			(stroke
				(width 0.1)
				(type default)
			)
			(layer "F.Fab")
		)
		(fp_line
			(start -0.67945 -0.305054)
			(end -0.12065 -0.305054)
			(stroke
				(width 0.1)
				(type default)
			)
			(layer "F.Fab")
		)
		(pad "1" smd circle
			(at -0.40005 0 180)
			(size 0 0)
			(layers "F.Cu" "F.Mask" "F.Paste")
			(net "FM_TPM_PRSNT_R_N")
		)
		(pad "2" smd circle
			(at 0.40005 0 180)
			(size 0 0)
			(layers "F.Cu" "F.Mask" "F.Paste")
			(net "FM_TPM_PRSNT_N")
		)
	)
)
